(kicad_pcb
	(version 20260206)
	(generator "pcbnew")
	(generator_version "10.0")
	(general
		(thickness 1.6)
		(legacy_teardrops no)
	)
	(paper "A4")
	(title_block
		(title "Bryce Canyon_F.DPB_16315-1-OCP.brd")
		(comment 1 "Bryce Canyon / footprints 1478-1484 of 2223")
	)
	(layers
		(0 "F.Cu" signal "TOP")
		(4 "In1.Cu" signal "L2GND")
		(6 "In2.Cu" signal "L3")
		(8 "In3.Cu" signal "L4GND")
		(10 "In4.Cu" signal "L5")
		(12 "In5.Cu" signal "L6VCC")
		(14 "In6.Cu" signal "L7VCC")
		(16 "In7.Cu" signal "L8")
		(18 "In8.Cu" signal "L9GND")
		(20 "In9.Cu" signal "L10")
		(22 "In10.Cu" signal "L11GND")
		(2 "B.Cu" signal "BOTTOM")
		(9 "F.Adhes" user "F.Adhesive")
		(11 "B.Adhes" user "B.Adhesive")
		(13 "F.Paste" user "Package Geometry/Pastemask Top")
		(15 "B.Paste" user "Package Geometry/Pastemask Bottom")
		(5 "F.SilkS" user "Ref Des/Silkscreen Top")
		(7 "B.SilkS" user "Ref Des/Silkscreen Bottom")
		(1 "F.Mask" user "Board Geometry/Soldermask Top")
		(3 "B.Mask" user "Board Geometry/Soldermask Bottom")
		(17 "Dwgs.User" user "User.Drawings")
		(19 "Cmts.User" user "User.Comments")
		(21 "Eco1.User" user "User.Eco1")
		(23 "Eco2.User" user "User.Eco2")
		(25 "Edge.Cuts" user "Board Geometry/Outline")
		(27 "Margin" user)
		(31 "F.CrtYd" user "Package Geometry/Place Bound Top")
		(29 "B.CrtYd" user "Package Geometry/Place Bound Bottom")
		(35 "F.Fab" user "Ref Des/Assembly Top")
		(33 "B.Fab" user "Ref Des/Assembly Bottom")
	)
	(footprint ""
		(layer "F.Cu")
		(at 15.261336 -130.30708 -90)
		(property "Reference" "R503"
			(at 0 0 270)
			(layer "F.SilkS")
			(hide yes)
			(effects
				(font
					(size 1.27 1.27)
				)
			)
		)
		(property "Value" "4K7R2J-2-GP"
			(at 0.064008 -3.993896 270)
			(unlocked yes)
			(layer "F.Fab")
			(hide yes)
			(effects
				(font
					(size 1.016 1.016)
					(thickness 0.1524)
				)
			)
		)
		(property "Device Type" "R402H16"
			(at 0.064008 -5.517896 270)
			(unlocked yes)
			(layer "F.Fab")
			(hide yes)
			(effects
				(font
					(size 1.016 1.016)
					(thickness 0.1524)
				)
			)
		)
		(duplicate_pad_numbers_are_jumpers no)
		(fp_line
			(start -0.508 -0.9398)
			(end -0.508 0.9398)
			(stroke
				(width 0.1524)
				(type default)
			)
			(layer "F.SilkS")
		)
		(fp_line
			(start 0.508 -0.9398)
			(end -0.508 -0.9398)
			(stroke
				(width 0.1524)
				(type default)
			)
			(layer "F.SilkS")
		)
		(fp_rect
			(start -0.508 0.9398)
			(end 0.508 -0.9398)
			(stroke
				(width 0)
				(type default)
			)
			(fill no)
			(layer "F.CrtYd")
		)
		(fp_rect
			(start -0.508 0.9398)
			(end 0.508 -0.9398)
			(stroke
				(width 0)
				(type default)
			)
			(fill no)
			(layer "F.Fab")
		)
		(pad "1" smd custom
			(at 0 -0.4445 270)
			(size 0.1397 0.1397)
			(layers "F.Cu" "F.Mask" "F.Paste")
			(net "DRIVE_A_12_FLT_LED")
			(options
				(clearance outline)
				(anchor circle)
			)
			(primitives
				(gr_poly
					(pts
						(arc
							(start -0.1778 -0.2794)
							(mid -0.249642 -0.249642)
							(end -0.2794 -0.1778)
						)
						(arc
							(start -0.2794 0.1778)
							(mid -0.249642 0.249642)
							(end -0.1778 0.2794)
						)
						(arc
							(start 0.1778 0.2794)
							(mid 0.249642 0.249642)
							(end 0.2794 0.1778)
						)
						(arc
							(start 0.2794 -0.1778)
							(mid 0.249642 -0.249642)
							(end 0.1778 -0.2794)
						)
					)
					(width 0)
					(fill yes)
				)
			)
		)
		(pad "2" smd custom
			(at 0 0.4445 270)
			(size 0.1397 0.1397)
			(layers "F.Cu" "F.Mask" "F.Paste")
			(net "GND")
			(options
				(clearance outline)
				(anchor circle)
			)
			(primitives
				(gr_poly
					(pts
						(arc
							(start -0.1778 -0.2794)
							(mid -0.249642 -0.249642)
							(end -0.2794 -0.1778)
						)
						(arc
							(start -0.2794 0.1778)
							(mid -0.249642 0.249642)
							(end -0.1778 0.2794)
						)
						(arc
							(start 0.1778 0.2794)
							(mid 0.249642 0.249642)
							(end 0.2794 0.1778)
						)
						(arc
							(start 0.2794 -0.1778)
							(mid 0.249642 -0.249642)
							(end 0.1778 -0.2794)
						)
					)
					(width 0)
					(fill yes)
				)
			)
		)
	)
	(footprint ""
		(layer "F.Cu")
		(at 244.200172 -273.205702)
		(property "Reference" ""
			(at 0 0 0)
			(layer "F.SilkS")
			(hide yes)
			(effects
				(font
					(size 1.27 1.27)
				)
			)
		)
		(property "Value" "*"
			(at -8.398764 -8.057642 0)
			(unlocked yes)
			(layer "F.Fab")
			(hide yes)
			(effects
				(font
					(size 1.016 1.016)
					(thickness 0.1524)
				)
			)
		)
		(duplicate_pad_numbers_are_jumpers no)
		(fp_poly
			(pts
				(arc
					(start 7.3152 0)
					(mid 0 7.3152)
					(end -7.3152 0)
				)
				(arc
					(start -7.3152 -5.9944)
					(mid 0 -13.3096)
					(end 7.3152 -5.9944)
				)
			)
			(stroke
				(width 0)
				(type default)
			)
			(fill no)
			(layer "B.CrtYd")
		)
		(fp_poly
			(pts
				(arc
					(start 7.3152 0)
					(mid 0 7.3152)
					(end -7.3152 0)
				)
				(arc
					(start -7.3152 -5.9944)
					(mid 0 -13.3096)
					(end 7.3152 -5.9944)
				)
			)
			(stroke
				(width 0)
				(type default)
			)
			(fill no)
			(layer "F.CrtYd")
		)
		(fp_poly
			(pts
				(arc
					(start 7.3152 0)
					(mid 0 7.3152)
					(end -7.3152 0)
				)
				(arc
					(start -7.3152 -5.9944)
					(mid 0 -13.3096)
					(end 7.3152 -5.9944)
				)
			)
			(stroke
				(width 0)
				(type default)
			)
			(fill no)
			(layer "B.Fab")
		)
		(fp_poly
			(pts
				(arc
					(start 7.3152 0)
					(mid 0 7.3152)
					(end -7.3152 0)
				)
				(arc
					(start -7.3152 -5.9944)
					(mid 0 -13.3096)
					(end 7.3152 -5.9944)
				)
			)
			(stroke
				(width 0)
				(type default)
			)
			(fill no)
			(layer "F.Fab")
		)
		(pad "1" thru_hole oval
			(at 0 0)
			(size 14.0208 20.0152)
			(drill 0.0254
				(offset 0 -2.9972)
			)
			(layers "*.Cu" "*.Mask")
			(remove_unused_layers no)
			(net "Net_66")
			(clearance -1.002284)
			(thermal_gap 0.1524)
			(padstack
				(mode front_inner_back)
				(layer "Inner"
					(shape custom)
					(size 2.928012 2.928012)
					(options
						(anchor circle)
					)
					(primitives
						(gr_poly
							(pts
								(arc
									(start 4.571746 -2.084324)
									(mid 0.000333 7.430372)
									(end -4.571492 -2.084324)
								)
								(arc
									(start -4.571492 -2.084324)
									(mid -3.570296 -3.611977)
									(end -2.875026 -5.30098)
								)
								(arc
									(start -2.875026 -5.30098)
									(mid 0.000217 -7.43089)
									(end 2.87528 -5.30098)
								)
								(arc
									(start 2.87528 -5.30098)
									(mid 3.570511 -3.611956)
									(end 4.571746 -2.084324)
								)
							)
							(width 0)
							(fill yes)
						)
					)
					(clearance 0.1524)
				)
				(layer "B.Cu"
					(shape oval)
					(size 14.0208 20.0152)
					(offset 0 -2.9972)
					(clearance -1.002284)
				)
			)
		)
		(zone
			(layers "F.Cu" "B.Cu" "In1.Cu" "In2.Cu" "In3.Cu" "In4.Cu" "In5.Cu" "In6.Cu"
				"In7.Cu" "In8.Cu" "In9.Cu" "In10.Cu"
			)
			(hatch none 0.5)
			(connect_pads
				(clearance 0)
			)
			(min_thickness 0.25)
			(keepout
				(tracks not_allowed)
				(vias allowed)
				(pads allowed)
				(copperpour not_allowed)
				(footprints allowed)
			)
			(placement
				(enabled no)
				(sheetname "")
			)
			(fill
				(thermal_gap 0.5)
				(thermal_bridge_width 0.5)
				(island_removal_mode 0)
			)
			(polygon
				(pts
					(arc
						(start 237.189772 -279.200102)
						(mid 244.200172 -286.210502)
						(end 251.210572 -279.200102)
					)
					(arc
						(start 251.210572 -273.205702)
						(mid 244.200172 -266.195302)
						(end 237.189772 -273.205702)
					)
				)
			)
		)
	)
	(footprint ""
		(layer "F.Cu")
		(at 396.60195 -188.954918 180)
		(property "Reference" "C306"
			(at 0 0 180)
			(layer "F.SilkS")
			(hide yes)
			(effects
				(font
					(size 1.27 1.27)
				)
			)
		)
		(property "Value" "SC4D7U25V5KX-1-GP"
			(at -0.0762 -6.1214 180)
			(unlocked yes)
			(layer "F.Fab")
			(hide yes)
			(effects
				(font
					(size 1.016 1.016)
					(thickness 0.1524)
				)
			)
		)
		(property "Device Type" "C805H58"
			(at -0.0762 -8.1534 180)
			(unlocked yes)
			(layer "F.Fab")
			(hide yes)
			(effects
				(font
					(size 1.016 1.016)
					(thickness 0.1524)
				)
			)
		)
		(duplicate_pad_numbers_are_jumpers no)
		(fp_line
			(start 0.635 0)
			(end -0.635 0)
			(stroke
				(width 0.508)
				(type default)
			)
			(layer "F.SilkS")
		)
		(fp_rect
			(start -0.9652 1.778)
			(end 0.9652 -1.778)
			(stroke
				(width 0)
				(type default)
			)
			(fill no)
			(layer "F.CrtYd")
		)
		(fp_poly
			(pts
				(xy -0.9652 -1.778) (xy 0.9652 -1.778) (xy 0.9652 1.778) (xy -0.9652 1.778)
			)
			(stroke
				(width 0)
				(type default)
			)
			(fill no)
			(layer "F.Fab")
		)
		(pad "1" smd rect
			(at 0 -0.9652 180)
			(size 1.397 1.143)
			(layers "F.Cu" "F.Mask" "F.Paste")
			(net "P12V_HDD20")
		)
		(pad "2" smd rect
			(at 0 0.9652 180)
			(size 1.397 1.143)
			(layers "F.Cu" "F.Mask" "F.Paste")
			(net "GND")
		)
	)
	(footprint ""
		(layer "F.Cu")
		(at 467.592918 -156.522674 180)
		(property "Reference" "R669"
			(at 0 0 180)
			(layer "F.SilkS")
			(hide yes)
			(effects
				(font
					(size 1.27 1.27)
				)
			)
		)
		(property "Value" "0R2J-2-GP"
			(at 0.064008 -3.993896 180)
			(unlocked yes)
			(layer "F.Fab")
			(hide yes)
			(effects
				(font
					(size 1.016 1.016)
					(thickness 0.1524)
				)
			)
		)
		(property "Device Type" "R402H16"
			(at 0.064008 -5.517896 180)
			(unlocked yes)
			(layer "F.Fab")
			(hide yes)
			(effects
				(font
					(size 1.016 1.016)
					(thickness 0.1524)
				)
			)
		)
		(duplicate_pad_numbers_are_jumpers no)
		(fp_line
			(start 0.508 -0.9398)
			(end -0.508 -0.9398)
			(stroke
				(width 0.1524)
				(type default)
			)
			(layer "F.SilkS")
		)
		(fp_line
			(start -0.508 -0.9398)
			(end -0.508 0.9398)
			(stroke
				(width 0.1524)
				(type default)
			)
			(layer "F.SilkS")
		)
		(fp_rect
			(start -0.508 0.9398)
			(end 0.508 -0.9398)
			(stroke
				(width 0)
				(type default)
			)
			(fill no)
			(layer "F.CrtYd")
		)
		(fp_rect
			(start -0.508 0.9398)
			(end 0.508 -0.9398)
			(stroke
				(width 0)
				(type default)
			)
			(fill no)
			(layer "F.Fab")
		)
		(pad "1" smd custom
			(at 0 -0.4445 180)
			(size 0.1397 0.1397)
			(layers "F.Cu" "F.Mask" "F.Paste")
			(net "DRIVE_A_23_PWR")
			(options
				(clearance outline)
				(anchor circle)
			)
			(primitives
				(gr_poly
					(pts
						(arc
							(start -0.1778 -0.2794)
							(mid -0.249642 -0.249642)
							(end -0.2794 -0.1778)
						)
						(arc
							(start -0.2794 0.1778)
							(mid -0.249642 0.249642)
							(end -0.1778 0.2794)
						)
						(arc
							(start 0.1778 0.2794)
							(mid 0.249642 0.249642)
							(end 0.2794 0.1778)
						)
						(arc
							(start 0.2794 -0.1778)
							(mid 0.249642 -0.249642)
							(end 0.1778 -0.2794)
						)
					)
					(width 0)
					(fill yes)
				)
			)
		)
		(pad "2" smd custom
			(at 0 0.4445 180)
			(size 0.1397 0.1397)
			(layers "F.Cu" "F.Mask" "F.Paste")
			(net "SW_PWR_R_HDD23")
			(options
				(clearance outline)
				(anchor circle)
			)
			(primitives
				(gr_poly
					(pts
						(arc
							(start -0.1778 -0.2794)
							(mid -0.249642 -0.249642)
							(end -0.2794 -0.1778)
						)
						(arc
							(start -0.2794 0.1778)
							(mid -0.249642 0.249642)
							(end -0.1778 0.2794)
						)
						(arc
							(start 0.1778 0.2794)
							(mid 0.249642 0.249642)
							(end 0.2794 0.1778)
						)
						(arc
							(start 0.2794 -0.1778)
							(mid 0.249642 -0.249642)
							(end 0.1778 -0.2794)
						)
					)
					(width 0)
					(fill yes)
				)
			)
		)
	)
	(footprint ""
		(layer "F.Cu")
		(at 265.734038 21.556218 -90)
		(property "Reference" "C76"
			(at 0 0 270)
			(layer "F.SilkS")
			(hide yes)
			(effects
				(font
					(size 1.27 1.27)
				)
			)
		)
		(property "Value" "SC47U16V0MX-GP"
			(at -0.00254 -4.78536 270)
			(unlocked yes)
			(layer "F.Fab")
			(hide yes)
			(effects
				(font
					(size 1.016 1.016)
					(thickness 0.1524)
				)
			)
		)
		(property "Device Type" "C1210H107"
			(at -0.00254 -6.38048 270)
			(unlocked yes)
			(layer "F.Fab")
			(hide yes)
			(effects
				(font
					(size 1.016 1.016)
					(thickness 0.1524)
				)
			)
		)
		(duplicate_pad_numbers_are_jumpers no)
		(fp_line
			(start -1.5748 2.3368)
			(end 1.5748 2.3368)
			(stroke
				(width 0.1524)
				(type default)
			)
			(layer "F.SilkS")
		)
		(fp_line
			(start 1.5748 2.3368)
			(end 1.5748 0.762)
			(stroke
				(width 0.1524)
				(type default)
			)
			(layer "F.SilkS")
		)
		(fp_line
			(start -1.5748 0.762)
			(end -1.5748 2.3368)
			(stroke
				(width 0.1524)
				(type default)
			)
			(layer "F.SilkS")
		)
		(fp_line
			(start 1.5748 -0.762)
			(end 1.5748 -2.3368)
			(stroke
				(width 0.1524)
				(type default)
			)
			(layer "F.SilkS")
		)
		(fp_line
			(start -1.5748 -2.3368)
			(end -1.5748 -0.762)
			(stroke
				(width 0.1524)
				(type default)
			)
			(layer "F.SilkS")
		)
		(fp_line
			(start 1.5748 -2.3368)
			(end -1.5748 -2.3368)
			(stroke
				(width 0.1524)
				(type default)
			)
			(layer "F.SilkS")
		)
		(fp_rect
			(start -1.651 2.413)
			(end 1.651 -2.413)
			(stroke
				(width 0)
				(type default)
			)
			(fill no)
			(layer "F.CrtYd")
		)
		(fp_poly
			(pts
				(xy 1.651 2.413) (xy 1.651 -2.413) (xy -1.651 -2.413) (xy -1.651 2.413)
			)
			(stroke
				(width 0)
				(type default)
			)
			(fill no)
			(layer "F.Fab")
		)
		(pad "1" smd rect
			(at 0 -1.4732 270)
			(size 2.794 1.397)
			(layers "F.Cu" "F.Mask" "F.Paste")
			(net "P5V_USB_B")
		)
		(pad "2" smd rect
			(at 0 1.4732 270)
			(size 2.794 1.397)
			(layers "F.Cu" "F.Mask" "F.Paste")
			(net "GND")
		)
	)
	(footprint ""
		(layer "F.Cu")
		(at 143.049498 -168.126918 -90)
		(property "Reference" "C256"
			(at 0 0 270)
			(layer "F.SilkS")
			(hide yes)
			(effects
				(font
					(size 1.27 1.27)
				)
			)
		)
		(property "Value" "SCD033U25V2KX-GP"
			(at 1.1811 -2.7051 270)
			(unlocked yes)
			(layer "F.Fab")
			(hide yes)
			(effects
				(font
					(size 1.016 1.016)
					(thickness 0.1524)
				)
			)
		)
		(property "Device Type" "C402H22"
			(at 1.1811 -4.2291 270)
			(unlocked yes)
			(layer "F.Fab")
			(hide yes)
			(effects
				(font
					(size 1.016 1.016)
					(thickness 0.1524)
				)
			)
		)
		(duplicate_pad_numbers_are_jumpers no)
		(fp_rect
			(start -0.4318 0.9525)
			(end 0.4318 -0.9525)
			(stroke
				(width 0)
				(type default)
			)
			(fill no)
			(layer "F.CrtYd")
		)
		(fp_rect
			(start -0.4318 0.9525)
			(end 0.4318 -0.9525)
			(stroke
				(width 0)
				(type default)
			)
			(fill no)
			(layer "F.Fab")
		)
		(pad "1" smd custom
			(at 0 -0.4445 270)
			(size 0.1524 0.1524)
			(layers "F.Cu" "F.Mask" "F.Paste")
			(net "SW_HDD_P16")
			(options
				(clearance outline)
				(anchor circle)
			)
			(primitives
				(gr_poly
					(pts
						(arc
							(start 0.3048 -0.2032)
							(mid 0.275042 -0.275042)
							(end 0.2032 -0.3048)
						)
						(arc
							(start -0.2032 -0.3048)
							(mid -0.275042 -0.275042)
							(end -0.3048 -0.2032)
						)
						(arc
							(start -0.3048 0.2032)
							(mid -0.275042 0.275042)
							(end -0.2032 0.3048)
						)
						(arc
							(start 0.2032 0.3048)
							(mid 0.275042 0.275042)
							(end 0.3048 0.2032)
						)
					)
					(width 0)
					(fill yes)
				)
			)
		)
		(pad "2" smd custom
			(at 0 0.4445 270)
			(size 0.1524 0.1524)
			(layers "F.Cu" "F.Mask" "F.Paste")
			(net "GND")
			(options
				(clearance outline)
				(anchor circle)
			)
			(primitives
				(gr_poly
					(pts
						(arc
							(start 0.3048 -0.2032)
							(mid 0.275042 -0.275042)
							(end 0.2032 -0.3048)
						)
						(arc
							(start -0.2032 -0.3048)
							(mid -0.275042 -0.275042)
							(end -0.3048 -0.2032)
						)
						(arc
							(start -0.3048 0.2032)
							(mid -0.275042 0.275042)
							(end -0.2032 0.3048)
						)
						(arc
							(start 0.2032 0.3048)
							(mid 0.275042 0.275042)
							(end 0.3048 0.2032)
						)
					)
					(width 0)
					(fill yes)
				)
			)
		)
	)
	(footprint ""
		(layer "F.Cu")
		(at 255.0414 14.292072)
		(property "Reference" "Q1"
			(at 0 0 0)
			(layer "F.SilkS")
			(hide yes)
			(effects
				(font
					(size 1.27 1.27)
				)
			)
		)
		(property "Value" "2N7002KDW-GP"
			(at -2.3622 -8.2042 0)
			(unlocked yes)
			(layer "F.Fab")
			(hide yes)
			(effects
				(font
					(size 1.016 1.016)
					(thickness 0.1524)
				)
			)
		)
		(property "Device Type" "SOT-363H44"
			(at -2.3622 -10.1092 0)
			(unlocked yes)
			(layer "F.Fab")
			(hide yes)
			(effects
				(font
					(size 1.016 1.016)
					(thickness 0.1524)
				)
			)
		)
		(duplicate_pad_numbers_are_jumpers no)
		(fp_line
			(start -1.4478 -1.7018)
			(end -1.4478 1.7018)
			(stroke
				(width 0.1524)
				(type default)
			)
			(layer "F.SilkS")
		)
		(fp_line
			(start -1.4478 1.7018)
			(end 1.4478 1.7018)
			(stroke
				(width 0.1524)
				(type default)
			)
			(layer "F.SilkS")
		)
		(fp_line
			(start -1.27 1.524)
			(end -1.27 0.6604)
			(stroke
				(width 0.4826)
				(type default)
			)
			(layer "F.SilkS")
		)
		(fp_line
			(start 1.4478 -1.7018)
			(end -1.4478 -1.7018)
			(stroke
				(width 0.1524)
				(type default)
			)
			(layer "F.SilkS")
		)
		(fp_line
			(start 1.4478 1.7018)
			(end 1.4478 -1.7018)
			(stroke
				(width 0.1524)
				(type default)
			)
			(layer "F.SilkS")
		)
		(fp_poly
			(pts
				(xy -1.524 -1.778) (xy 1.524 -1.778) (xy 1.524 1.778) (xy -1.524 1.778)
			)
			(stroke
				(width 0)
				(type default)
			)
			(fill no)
			(layer "F.CrtYd")
		)
		(fp_poly
			(pts
				(xy -1.524 -1.778) (xy 1.524 -1.778) (xy 1.524 1.778) (xy -1.524 1.778)
			)
			(stroke
				(width 0)
				(type default)
			)
			(fill no)
			(layer "F.Fab")
		)
		(pad "1" smd rect
			(at -0.65024 0.9398)
			(size 0.4064 1.016)
			(layers "F.Cu" "F.Mask" "F.Paste")
			(net "GND")
		)
		(pad "2" smd rect
			(at 0 0.9398)
			(size 0.4064 1.016)
			(layers "F.Cu" "F.Mask" "F.Paste")
			(net "SCC_A_PWR_LED")
		)
		(pad "3" smd rect
			(at 0.65024 0.9398)
			(size 0.4064 1.016)
			(layers "F.Cu" "F.Mask" "F.Paste")
			(net "SYS_PWR_LED_A")
		)
		(pad "4" smd rect
			(at 0.65024 -0.9398)
			(size 0.4064 1.016)
			(layers "F.Cu" "F.Mask" "F.Paste")
			(net "GND")
		)
		(pad "5" smd rect
			(at 0 -0.9398)
			(size 0.4064 1.016)
			(layers "F.Cu" "F.Mask" "F.Paste")
			(net "IOM_A_PWR_LED")
		)
		(pad "6" smd rect
			(at -0.65024 -0.9398)
			(size 0.4064 1.016)
			(layers "F.Cu" "F.Mask" "F.Paste")
			(net "SYS_PWR_LED_A")
		)
	)
)
